FILE_TYPE = CONNECTIVITY;
{Allegro Design Entry HDL 17.4-2019 S026 (4007227) 1/17/2022}
"PAGE_NUMBER" = 131;
0"NC";
END.
